FILE_TYPE=LIBRARY_PARTS;
primitive 'SMC-CONN60A-22-GP';
  pin
    '1':
      PIN_NUMBER='(1)';
      PIN_TYPE='ANALOG';
      NO_LOAD_CHECK='Both';
      NO_IO_CHECK='Both';
      NO_ASSERT_CHECK='TRUE';
      NO_DIR_CHECK='TRUE';
      ALLOW_CONNECT='TRUE';
    '3':
      PIN_NUMBER='(3)';
      PIN_TYPE='ANALOG';
      NO_LOAD_CHECK='Both';
      NO_IO_CHECK='Both';
      NO_ASSERT_CHECK='TRUE';
      NO_DIR_CHECK='TRUE';
      ALLOW_CONNECT='TRUE';
    '5':
      PIN_NUMBER='(5)';
      PIN_TYPE='ANALOG';
      NO_LOAD_CHECK='Both';
      NO_IO_CHECK='Both';
      NO_ASSERT_CHECK='TRUE';
      NO_DIR_CHECK='TRUE';
      ALLOW_CONNECT='TRUE';
    '7':
      PIN_NUMBER='(7)';
      PIN_TYPE='ANALOG';
      NO_LOAD_CHECK='Both';
      NO_IO_CHECK='Both';
      NO_ASSERT_CHECK='TRUE';
      NO_DIR_CHECK='TRUE';
      ALLOW_CONNECT='TRUE';
    '2':
      PIN_NUMBER='(2)';
      PIN_TYPE='ANALOG';
      NO_LOAD_CHECK='Both';
      NO_IO_CHECK='Both';
      NO_ASSERT_CHECK='TRUE';
      NO_DIR_CHECK='TRUE';
      ALLOW_CONNECT='TRUE';
    '4':
      PIN_NUMBER='(4)';
      PIN_TYPE='ANALOG';
      NO_LOAD_CHECK='Both';
      NO_IO_CHECK='Both';
      NO_ASSERT_CHECK='TRUE';
      NO_DIR_CHECK='TRUE';
      ALLOW_CONNECT='TRUE';
    '6':
      PIN_NUMBER='(6)';
      PIN_TYPE='ANALOG';
      NO_LOAD_CHECK='Both';
      NO_IO_CHECK='Both';
      NO_ASSERT_CHECK='TRUE';
      NO_DIR_CHECK='TRUE';
      ALLOW_CONNECT='TRUE';
    '8':
      PIN_NUMBER='(8)';
      PIN_TYPE='ANALOG';
      NO_LOAD_CHECK='Both';
      NO_IO_CHECK='Both';
      NO_ASSERT_CHECK='TRUE';
      NO_DIR_CHECK='TRUE';
      ALLOW_CONNECT='TRUE';
    '9':
      PIN_NUMBER='(9)';
      PIN_TYPE='ANALOG';
      NO_LOAD_CHECK='Both';
      NO_IO_CHECK='Both';
      NO_ASSERT_CHECK='TRUE';
      NO_DIR_CHECK='TRUE';
      ALLOW_CONNECT='TRUE';
    '11':
      PIN_NUMBER='(11)';
      PIN_TYPE='ANALOG';
      NO_LOAD_CHECK='Both';
      NO_IO_CHECK='Both';
      NO_ASSERT_CHECK='TRUE';
      NO_DIR_CHECK='TRUE';
      ALLOW_CONNECT='TRUE';
    '13':
      PIN_NUMBER='(13)';
      PIN_TYPE='ANALOG';
      NO_LOAD_CHECK='Both';
      NO_IO_CHECK='Both';
      NO_ASSERT_CHECK='TRUE';
      NO_DIR_CHECK='TRUE';
      ALLOW_CONNECT='TRUE';
    '15':
      PIN_NUMBER='(15)';
      PIN_TYPE='ANALOG';
      NO_LOAD_CHECK='Both';
      NO_IO_CHECK='Both';
      NO_ASSERT_CHECK='TRUE';
      NO_DIR_CHECK='TRUE';
      ALLOW_CONNECT='TRUE';
    '17':
      PIN_NUMBER='(17)';
      PIN_TYPE='ANALOG';
      NO_LOAD_CHECK='Both';
      NO_IO_CHECK='Both';
      NO_ASSERT_CHECK='TRUE';
      NO_DIR_CHECK='TRUE';
      ALLOW_CONNECT='TRUE';
    '19':
      PIN_NUMBER='(19)';
      PIN_TYPE='ANALOG';
      NO_LOAD_CHECK='Both';
      NO_IO_CHECK='Both';
      NO_ASSERT_CHECK='TRUE';
      NO_DIR_CHECK='TRUE';
      ALLOW_CONNECT='TRUE';
    '21':
      PIN_NUMBER='(21)';
      PIN_TYPE='ANALOG';
      NO_LOAD_CHECK='Both';
      NO_IO_CHECK='Both';
      NO_ASSERT_CHECK='TRUE';
      NO_DIR_CHECK='TRUE';
      ALLOW_CONNECT='TRUE';
    '23':
      PIN_NUMBER='(23)';
      PIN_TYPE='ANALOG';
      NO_LOAD_CHECK='Both';
      NO_IO_CHECK='Both';
      NO_ASSERT_CHECK='TRUE';
      NO_DIR_CHECK='TRUE';
      ALLOW_CONNECT='TRUE';
    '25':
      PIN_NUMBER='(25)';
      PIN_TYPE='ANALOG';
      NO_LOAD_CHECK='Both';
      NO_IO_CHECK='Both';
      NO_ASSERT_CHECK='TRUE';
      NO_DIR_CHECK='TRUE';
      ALLOW_CONNECT='TRUE';
    '27':
      PIN_NUMBER='(27)';
      PIN_TYPE='ANALOG';
      NO_LOAD_CHECK='Both';
      NO_IO_CHECK='Both';
      NO_ASSERT_CHECK='TRUE';
      NO_DIR_CHECK='TRUE';
      ALLOW_CONNECT='TRUE';
    '29':
      PIN_NUMBER='(29)';
      PIN_TYPE='ANALOG';
      NO_LOAD_CHECK='Both';
      NO_IO_CHECK='Both';
      NO_ASSERT_CHECK='TRUE';
      NO_DIR_CHECK='TRUE';
      ALLOW_CONNECT='TRUE';
    '31':
      PIN_NUMBER='(31)';
      PIN_TYPE='ANALOG';
      NO_LOAD_CHECK='Both';
      NO_IO_CHECK='Both';
      NO_ASSERT_CHECK='TRUE';
      NO_DIR_CHECK='TRUE';
      ALLOW_CONNECT='TRUE';
    '33':
      PIN_NUMBER='(33)';
      PIN_TYPE='ANALOG';
      NO_LOAD_CHECK='Both';
      NO_IO_CHECK='Both';
      NO_ASSERT_CHECK='TRUE';
      NO_DIR_CHECK='TRUE';
      ALLOW_CONNECT='TRUE';
    '35':
      PIN_NUMBER='(35)';
      PIN_TYPE='ANALOG';
      NO_LOAD_CHECK='Both';
      NO_IO_CHECK='Both';
      NO_ASSERT_CHECK='TRUE';
      NO_DIR_CHECK='TRUE';
      ALLOW_CONNECT='TRUE';
    '37':
      PIN_NUMBER='(37)';
      PIN_TYPE='ANALOG';
      NO_LOAD_CHECK='Both';
      NO_IO_CHECK='Both';
      NO_ASSERT_CHECK='TRUE';
      NO_DIR_CHECK='TRUE';
      ALLOW_CONNECT='TRUE';
    '39':
      PIN_NUMBER='(39)';
      PIN_TYPE='ANALOG';
      NO_LOAD_CHECK='Both';
      NO_IO_CHECK='Both';
      NO_ASSERT_CHECK='TRUE';
      NO_DIR_CHECK='TRUE';
      ALLOW_CONNECT='TRUE';
    '41':
      PIN_NUMBER='(41)';
      PIN_TYPE='ANALOG';
      NO_LOAD_CHECK='Both';
      NO_IO_CHECK='Both';
      NO_ASSERT_CHECK='TRUE';
      NO_DIR_CHECK='TRUE';
      ALLOW_CONNECT='TRUE';
    '43':
      PIN_NUMBER='(43)';
      PIN_TYPE='ANALOG';
      NO_LOAD_CHECK='Both';
      NO_IO_CHECK='Both';
      NO_ASSERT_CHECK='TRUE';
      NO_DIR_CHECK='TRUE';
      ALLOW_CONNECT='TRUE';
    '45':
      PIN_NUMBER='(45)';
      PIN_TYPE='ANALOG';
      NO_LOAD_CHECK='Both';
      NO_IO_CHECK='Both';
      NO_ASSERT_CHECK='TRUE';
      NO_DIR_CHECK='TRUE';
      ALLOW_CONNECT='TRUE';
    '47':
      PIN_NUMBER='(47)';
      PIN_TYPE='ANALOG';
      NO_LOAD_CHECK='Both';
      NO_IO_CHECK='Both';
      NO_ASSERT_CHECK='TRUE';
      NO_DIR_CHECK='TRUE';
      ALLOW_CONNECT='TRUE';
    '49':
      PIN_NUMBER='(49)';
      PIN_TYPE='ANALOG';
      NO_LOAD_CHECK='Both';
      NO_IO_CHECK='Both';
      NO_ASSERT_CHECK='TRUE';
      NO_DIR_CHECK='TRUE';
      ALLOW_CONNECT='TRUE';
    '51':
      PIN_NUMBER='(51)';
      PIN_TYPE='ANALOG';
      NO_LOAD_CHECK='Both';
      NO_IO_CHECK='Both';
      NO_ASSERT_CHECK='TRUE';
      NO_DIR_CHECK='TRUE';
      ALLOW_CONNECT='TRUE';
    '53':
      PIN_NUMBER='(53)';
      PIN_TYPE='ANALOG';
      NO_LOAD_CHECK='Both';
      NO_IO_CHECK='Both';
      NO_ASSERT_CHECK='TRUE';
      NO_DIR_CHECK='TRUE';
      ALLOW_CONNECT='TRUE';
    '55':
      PIN_NUMBER='(55)';
      PIN_TYPE='ANALOG';
      NO_LOAD_CHECK='Both';
      NO_IO_CHECK='Both';
      NO_ASSERT_CHECK='TRUE';
      NO_DIR_CHECK='TRUE';
      ALLOW_CONNECT='TRUE';
    '57':
      PIN_NUMBER='(57)';
      PIN_TYPE='ANALOG';
      NO_LOAD_CHECK='Both';
      NO_IO_CHECK='Both';
      NO_ASSERT_CHECK='TRUE';
      NO_DIR_CHECK='TRUE';
      ALLOW_CONNECT='TRUE';
    '59':
      PIN_NUMBER='(59)';
      PIN_TYPE='ANALOG';
      NO_LOAD_CHECK='Both';
      NO_IO_CHECK='Both';
      NO_ASSERT_CHECK='TRUE';
      NO_DIR_CHECK='TRUE';
      ALLOW_CONNECT='TRUE';
    '10':
      PIN_NUMBER='(10)';
      PIN_TYPE='ANALOG';
      NO_LOAD_CHECK='Both';
      NO_IO_CHECK='Both';
      NO_ASSERT_CHECK='TRUE';
      NO_DIR_CHECK='TRUE';
      ALLOW_CONNECT='TRUE';
    '12':
      PIN_NUMBER='(12)';
      PIN_TYPE='ANALOG';
      NO_LOAD_CHECK='Both';
      NO_IO_CHECK='Both';
      NO_ASSERT_CHECK='TRUE';
      NO_DIR_CHECK='TRUE';
      ALLOW_CONNECT='TRUE';
    '14':
      PIN_NUMBER='(14)';
      PIN_TYPE='ANALOG';
      NO_LOAD_CHECK='Both';
      NO_IO_CHECK='Both';
      NO_ASSERT_CHECK='TRUE';
      NO_DIR_CHECK='TRUE';
      ALLOW_CONNECT='TRUE';
    '16':
      PIN_NUMBER='(16)';
      PIN_TYPE='ANALOG';
      NO_LOAD_CHECK='Both';
      NO_IO_CHECK='Both';
      NO_ASSERT_CHECK='TRUE';
      NO_DIR_CHECK='TRUE';
      ALLOW_CONNECT='TRUE';
    '18':
      PIN_NUMBER='(18)';
      PIN_TYPE='ANALOG';
      NO_LOAD_CHECK='Both';
      NO_IO_CHECK='Both';
      NO_ASSERT_CHECK='TRUE';
      NO_DIR_CHECK='TRUE';
      ALLOW_CONNECT='TRUE';
    '20':
      PIN_NUMBER='(20)';
      PIN_TYPE='ANALOG';
      NO_LOAD_CHECK='Both';
      NO_IO_CHECK='Both';
      NO_ASSERT_CHECK='TRUE';
      NO_DIR_CHECK='TRUE';
      ALLOW_CONNECT='TRUE';
    '22':
      PIN_NUMBER='(22)';
      PIN_TYPE='ANALOG';
      NO_LOAD_CHECK='Both';
      NO_IO_CHECK='Both';
      NO_ASSERT_CHECK='TRUE';
      NO_DIR_CHECK='TRUE';
      ALLOW_CONNECT='TRUE';
    '24':
      PIN_NUMBER='(24)';
      PIN_TYPE='ANALOG';
      NO_LOAD_CHECK='Both';
      NO_IO_CHECK='Both';
      NO_ASSERT_CHECK='TRUE';
      NO_DIR_CHECK='TRUE';
      ALLOW_CONNECT='TRUE';
    '26':
      PIN_NUMBER='(26)';
      PIN_TYPE='ANALOG';
      NO_LOAD_CHECK='Both';
      NO_IO_CHECK='Both';
      NO_ASSERT_CHECK='TRUE';
      NO_DIR_CHECK='TRUE';
      ALLOW_CONNECT='TRUE';
    '28':
      PIN_NUMBER='(28)';
      PIN_TYPE='ANALOG';
      NO_LOAD_CHECK='Both';
      NO_IO_CHECK='Both';
      NO_ASSERT_CHECK='TRUE';
      NO_DIR_CHECK='TRUE';
      ALLOW_CONNECT='TRUE';
    '30':
      PIN_NUMBER='(30)';
      PIN_TYPE='ANALOG';
      NO_LOAD_CHECK='Both';
      NO_IO_CHECK='Both';
      NO_ASSERT_CHECK='TRUE';
      NO_DIR_CHECK='TRUE';
      ALLOW_CONNECT='TRUE';
    '32':
      PIN_NUMBER='(32)';
      PIN_TYPE='ANALOG';
      NO_LOAD_CHECK='Both';
      NO_IO_CHECK='Both';
      NO_ASSERT_CHECK='TRUE';
      NO_DIR_CHECK='TRUE';
      ALLOW_CONNECT='TRUE';
    '34':
      PIN_NUMBER='(34)';
      PIN_TYPE='ANALOG';
      NO_LOAD_CHECK='Both';
      NO_IO_CHECK='Both';
      NO_ASSERT_CHECK='TRUE';
      NO_DIR_CHECK='TRUE';
      ALLOW_CONNECT='TRUE';
    '36':
      PIN_NUMBER='(36)';
      PIN_TYPE='ANALOG';
      NO_LOAD_CHECK='Both';
      NO_IO_CHECK='Both';
      NO_ASSERT_CHECK='TRUE';
      NO_DIR_CHECK='TRUE';
      ALLOW_CONNECT='TRUE';
    '38':
      PIN_NUMBER='(38)';
      PIN_TYPE='ANALOG';
      NO_LOAD_CHECK='Both';
      NO_IO_CHECK='Both';
      NO_ASSERT_CHECK='TRUE';
      NO_DIR_CHECK='TRUE';
      ALLOW_CONNECT='TRUE';
    '40':
      PIN_NUMBER='(40)';
      PIN_TYPE='ANALOG';
      NO_LOAD_CHECK='Both';
      NO_IO_CHECK='Both';
      NO_ASSERT_CHECK='TRUE';
      NO_DIR_CHECK='TRUE';
      ALLOW_CONNECT='TRUE';
    '42':
      PIN_NUMBER='(42)';
      PIN_TYPE='ANALOG';
      NO_LOAD_CHECK='Both';
      NO_IO_CHECK='Both';
      NO_ASSERT_CHECK='TRUE';
      NO_DIR_CHECK='TRUE';
      ALLOW_CONNECT='TRUE';
    '44':
      PIN_NUMBER='(44)';
      PIN_TYPE='ANALOG';
      NO_LOAD_CHECK='Both';
      NO_IO_CHECK='Both';
      NO_ASSERT_CHECK='TRUE';
      NO_DIR_CHECK='TRUE';
      ALLOW_CONNECT='TRUE';
    '46':
      PIN_NUMBER='(46)';
      PIN_TYPE='ANALOG';
      NO_LOAD_CHECK='Both';
      NO_IO_CHECK='Both';
      NO_ASSERT_CHECK='TRUE';
      NO_DIR_CHECK='TRUE';
      ALLOW_CONNECT='TRUE';
    '48':
      PIN_NUMBER='(48)';
      PIN_TYPE='ANALOG';
      NO_LOAD_CHECK='Both';
      NO_IO_CHECK='Both';
      NO_ASSERT_CHECK='TRUE';
      NO_DIR_CHECK='TRUE';
      ALLOW_CONNECT='TRUE';
    '50':
      PIN_NUMBER='(50)';
      PIN_TYPE='ANALOG';
      NO_LOAD_CHECK='Both';
      NO_IO_CHECK='Both';
      NO_ASSERT_CHECK='TRUE';
      NO_DIR_CHECK='TRUE';
      ALLOW_CONNECT='TRUE';
    '52':
      PIN_NUMBER='(52)';
      PIN_TYPE='ANALOG';
      NO_LOAD_CHECK='Both';
      NO_IO_CHECK='Both';
      NO_ASSERT_CHECK='TRUE';
      NO_DIR_CHECK='TRUE';
      ALLOW_CONNECT='TRUE';
    '54':
      PIN_NUMBER='(54)';
      PIN_TYPE='ANALOG';
      NO_LOAD_CHECK='Both';
      NO_IO_CHECK='Both';
      NO_ASSERT_CHECK='TRUE';
      NO_DIR_CHECK='TRUE';
      ALLOW_CONNECT='TRUE';
    '56':
      PIN_NUMBER='(56)';
      PIN_TYPE='ANALOG';
      NO_LOAD_CHECK='Both';
      NO_IO_CHECK='Both';
      NO_ASSERT_CHECK='TRUE';
      NO_DIR_CHECK='TRUE';
      ALLOW_CONNECT='TRUE';
    '58':
      PIN_NUMBER='(58)';
      PIN_TYPE='ANALOG';
      NO_LOAD_CHECK='Both';
      NO_IO_CHECK='Both';
      NO_ASSERT_CHECK='TRUE';
      NO_DIR_CHECK='TRUE';
      ALLOW_CONNECT='TRUE';
    '60':
      PIN_NUMBER='(60)';
      PIN_TYPE='ANALOG';
      NO_LOAD_CHECK='Both';
      NO_IO_CHECK='Both';
      NO_ASSERT_CHECK='TRUE';
      NO_DIR_CHECK='TRUE';
      ALLOW_CONNECT='TRUE';
    'NP1':
      PIN_NUMBER='(NP1)';
      PIN_TYPE='ANALOG';
      NO_LOAD_CHECK='Both';
      NO_IO_CHECK='Both';
      NO_ASSERT_CHECK='TRUE';
      NO_DIR_CHECK='TRUE';
      ALLOW_CONNECT='TRUE';
    'NP2':
      PIN_NUMBER='(NP2)';
      PIN_TYPE='ANALOG';
      NO_LOAD_CHECK='Both';
      NO_IO_CHECK='Both';
      NO_ASSERT_CHECK='TRUE';
      NO_DIR_CHECK='TRUE';
      ALLOW_CONNECT='TRUE';
    'PTH1':
      PIN_NUMBER='(PTH1)';
      PIN_TYPE='ANALOG';
      NO_LOAD_CHECK='Both';
      NO_IO_CHECK='Both';
      NO_ASSERT_CHECK='TRUE';
      NO_DIR_CHECK='TRUE';
      ALLOW_CONNECT='TRUE';
    'PTH2':
      PIN_NUMBER='(PTH2)';
      PIN_TYPE='ANALOG';
      NO_LOAD_CHECK='Both';
      NO_IO_CHECK='Both';
      NO_ASSERT_CHECK='TRUE';
      NO_DIR_CHECK='TRUE';
      ALLOW_CONNECT='TRUE';
  end_pin;
  body
    PART_NAME='SMC-CONN60A-22-GP';
    BODY_NAME='SMC-CONN60A-22-GP';
    PHYS_DES_PREFIX='CN';
    CLASS='IO';
  end_body;
end_primitive;

END.
